# S9S_MB_2U (Grand Teton) — schematic netlist excerpt (pin names and nets, part order shuffled) for the footprints in the layout excerpt that follows; sources: Cadence DE-HDL packaged netlist, KiCad conversion of 03242023_DA0F0TMBIJ0_F0T_Motherboard_J_brd_V01_OCP.brd

R1655  Q_RES  10K 1% CHIP  pkg 0402LF  page 260 : A = P12V_AUX ; B = PWRGD_P5V_ISO_R
C1919  Q_CAP  0.01UF 50V 10% X7R  pkg C0402  page 217 : A = VCC_PLD_CORE ; B = GND

(kicad_pcb
	(version 20260206)
	(generator "pcbnew")
	(generator_version "10.0")
	(general
		(thickness 1.6)
		(legacy_teardrops no)
	)
	(paper "A4")
	(title_block
		(title "03242023_DA0F0TMBIJ0_F0T_Motherboard_J_brd_V01_OCP.brd")
		(comment 1 "Grand Teton / footprints 5071-5072 of 6105")
	)
	(layers
		(0 "F.Cu" signal "TOP")
		(4 "In1.Cu" signal "GND")
		(6 "In2.Cu" signal "IN1")
		(8 "In3.Cu" signal "GND1")
		(10 "In4.Cu" signal "IN2")
		(12 "In5.Cu" signal "GND2")
		(14 "In6.Cu" signal "IN3")
		(16 "In7.Cu" signal "GND3")
		(18 "In8.Cu" signal "VCC")
		(20 "In9.Cu" signal "VCC1")
		(22 "In10.Cu" signal "GND4")
		(24 "In11.Cu" signal "IN4")
		(26 "In12.Cu" signal "GND5")
		(28 "In13.Cu" signal "IN5")
		(30 "In14.Cu" signal "GND6")
		(32 "In15.Cu" signal "IN6")
		(34 "In16.Cu" signal "GND7")
		(2 "B.Cu" signal "BOTTOM")
		(9 "F.Adhes" user "F.Adhesive")
		(11 "B.Adhes" user "B.Adhesive")
		(13 "F.Paste" user "Package Geometry/Pastemask Top")
		(15 "B.Paste" user "Package Geometry/Pastemask Bottom")
		(5 "F.SilkS" user "Ref Des/Silkscreen Top")
		(7 "B.SilkS" user "Ref Des/Silkscreen Bottom")
		(1 "F.Mask" user "Board Geometry/Soldermask Top")
		(3 "B.Mask" user "Board Geometry/Soldermask Bottom")
		(17 "Dwgs.User" user "User.Drawings")
		(19 "Cmts.User" user "User.Comments")
		(21 "Eco1.User" user "User.Eco1")
		(23 "Eco2.User" user "User.Eco2")
		(25 "Edge.Cuts" user "Board Geometry/Outline")
		(27 "Margin" user)
		(31 "F.CrtYd" user "Package Geometry/Place Bound Top")
		(29 "B.CrtYd" user "Package Geometry/Place Bound Bottom")
		(35 "F.Fab" user "Ref Des/Assembly Top")
		(33 "B.Fab" user "Ref Des/Assembly Bottom")
	)
	(footprint ""
		(layer "B.Cu")
		(at 433.61864 -52.2478 -90)
		(property "Reference" "R1655"
			(at 0 0 90)
			(layer "B.SilkS")
			(hide yes)
			(effects
				(font
					(size 1.27 1.27)
				)
				(justify mirror)
			)
		)
		(property "Value" ""
			(at 0 0 90)
			(layer "B.Fab")
			(effects
				(font
					(size 1.27 1.27)
				)
				(justify mirror)
			)
		)
		(duplicate_pad_numbers_are_jumpers no)
		(fp_line
			(start -0.7874 0.4064)
			(end 0.7874 0.4064)
			(stroke
				(width 0.1524)
				(type default)
			)
			(layer "B.SilkS")
		)
		(fp_line
			(start 0.7874 0.4064)
			(end 0.7874 -0.4064)
			(stroke
				(width 0.1524)
				(type default)
			)
			(layer "B.SilkS")
		)
		(fp_line
			(start -0.7874 -0.4064)
			(end -0.7874 0.4064)
			(stroke
				(width 0.1524)
				(type default)
			)
			(layer "B.SilkS")
		)
		(fp_line
			(start 0.7874 -0.4064)
			(end -0.7874 -0.4064)
			(stroke
				(width 0.1524)
				(type default)
			)
			(layer "B.SilkS")
		)
		(fp_line
			(start -0.67945 0.3048)
			(end -0.120396 0.3048)
			(stroke
				(width 0.1)
				(type default)
			)
			(layer "B.Fab")
		)
		(fp_line
			(start -0.120396 0.3048)
			(end -0.120396 0.2794)
			(stroke
				(width 0.1)
				(type default)
			)
			(layer "B.Fab")
		)
		(fp_line
			(start 0.12065 0.3048)
			(end 0.67945 0.3048)
			(stroke
				(width 0.1)
				(type default)
			)
			(layer "B.Fab")
		)
		(fp_line
			(start 0.67945 0.3048)
			(end 0.67945 -0.305054)
			(stroke
				(width 0.1)
				(type default)
			)
			(layer "B.Fab")
		)
		(fp_line
			(start -0.120396 0.2794)
			(end 0.12065 0.2794)
			(stroke
				(width 0.1)
				(type default)
			)
			(layer "B.Fab")
		)
		(fp_line
			(start 0.12065 0.2794)
			(end 0.12065 0.3048)
			(stroke
				(width 0.1)
				(type default)
			)
			(layer "B.Fab")
		)
		(fp_line
			(start -0.12065 -0.2794)
			(end -0.12065 -0.3048)
			(stroke
				(width 0.1)
				(type default)
			)
			(layer "B.Fab")
		)
		(fp_line
			(start 0.12065 -0.2794)
			(end -0.12065 -0.2794)
			(stroke
				(width 0.1)
				(type default)
			)
			(layer "B.Fab")
		)
		(fp_line
			(start -0.67945 -0.3048)
			(end -0.67945 0.3048)
			(stroke
				(width 0.1)
				(type default)
			)
			(layer "B.Fab")
		)
		(fp_line
			(start -0.12065 -0.3048)
			(end -0.67945 -0.3048)
			(stroke
				(width 0.1)
				(type default)
			)
			(layer "B.Fab")
		)
		(fp_line
			(start 0.12065 -0.305054)
			(end 0.12065 -0.2794)
			(stroke
				(width 0.1)
				(type default)
			)
			(layer "B.Fab")
		)
		(fp_line
			(start 0.67945 -0.305054)
			(end 0.12065 -0.305054)
			(stroke
				(width 0.1)
				(type default)
			)
			(layer "B.Fab")
		)
		(pad "1" smd circle
			(at 0.40005 0 90)
			(size 0 0)
			(layers "B.Cu" "B.Mask" "B.Paste")
			(net "P12V_AUX")
		)
		(pad "2" smd circle
			(at -0.40005 0 90)
			(size 0 0)
			(layers "B.Cu" "B.Mask" "B.Paste")
			(net "PWRGD_P5V_ISO_R")
		)
	)
	(footprint ""
		(layer "B.Cu")
		(at 178.9557 -114.17554 -90)
		(property "Reference" "C1919"
			(at 0 0 90)
			(layer "B.SilkS")
			(hide yes)
			(effects
				(font
					(size 1.27 1.27)
				)
				(justify mirror)
			)
		)
		(property "Value" ""
			(at 0 0 90)
			(layer "B.Fab")
			(effects
				(font
					(size 1.27 1.27)
				)
				(justify mirror)
			)
		)
		(duplicate_pad_numbers_are_jumpers no)
		(fp_line
			(start -0.69215 0.2921)
			(end 0.69215 0.2921)
			(stroke
				(width 0.1524)
				(type default)
			)
			(layer "B.SilkS")
		)
		(fp_line
			(start 0.69215 0.2921)
			(end 0.69215 -0.2921)
			(stroke
				(width 0.1524)
				(type default)
			)
			(layer "B.SilkS")
		)
		(fp_line
			(start -0.69215 -0.2921)
			(end -0.69215 0.2921)
			(stroke
				(width 0.1524)
				(type default)
			)
			(layer "B.SilkS")
		)
		(fp_line
			(start 0.69215 -0.2921)
			(end -0.69215 -0.2921)
			(stroke
				(width 0.1524)
				(type default)
			)
			(layer "B.SilkS")
		)
		(fp_line
			(start -0.51435 0.2794)
			(end 0.51435 0.2794)
			(stroke
				(width 0.1)
				(type default)
			)
			(layer "B.Fab")
		)
		(fp_line
			(start 0.51435 0.2794)
			(end 0.51435 -0.2794)
			(stroke
				(width 0.1)
				(type default)
			)
			(layer "B.Fab")
		)
		(fp_line
			(start -0.51435 -0.2794)
			(end -0.51435 0.2794)
			(stroke
				(width 0.1)
				(type default)
			)
			(layer "B.Fab")
		)
		(fp_line
			(start 0.51435 -0.2794)
			(end -0.51435 -0.2794)
			(stroke
				(width 0.1)
				(type default)
			)
			(layer "B.Fab")
		)
		(pad "1" smd circle
			(at 0.40005 0 90)
			(size 0 0)
			(layers "B.Cu" "B.Mask" "B.Paste")
			(net "VCC_PLD_CORE")
		)
		(pad "2" smd circle
			(at -0.40005 0 90)
			(size 0 0)
			(layers "B.Cu" "B.Mask" "B.Paste")
			(net "GND")
		)
		(zone
			(layer "B.Cu")
			(hatch none 0.5)
			(connect_pads
				(clearance 0)
			)
			(min_thickness 0.25)
			(keepout
				(tracks not_allowed)
				(vias allowed)
				(pads allowed)
				(copperpour not_allowed)
				(footprints allowed)
			)
			(placement
				(enabled no)
				(sheetname "")
			)
			(fill
				(thermal_gap 0.5)
				(thermal_bridge_width 0.5)
				(island_removal_mode 0)
			)
			(polygon
				(pts
					(xy 178.86807 -113.98504) (xy 178.809904 -114.07648) (xy 178.809904 -114.27587) (xy 178.86807 -114.36604)
					(xy 179.04333 -114.36604) (xy 179.10175 -114.27587) (xy 179.10175 -114.07648) (xy 179.043584 -113.98504)
				)
			)
		)
	)
)
